# T6G (Grand Teton) — schematic netlist excerpt (pin names and nets, part order shuffled) for the footprints in the layout excerpt that follows; sources: Cadence DE-HDL packaged netlist, KiCad conversion of 04192023_DAF0TMB3IC0_F0TG_MB_C_brd_V02_OCP.brd

C2309  Q_CAP  22UF 4V 20% X6S  pkg C0402  page 73 : A = PVDDCR_CPU0_P1 ; B = GND
C2448  Q_CAP  22UF 4V 20% X6S  pkg C0402  page 74 : A = PVDDCR_SOC_P1 ; B = GND
C797  Q_CAP  1UF 4V 20% X6S  pkg 0201  page 301 : A = P0V9_CPU0_RT2_2A ; B = GND

(kicad_pcb
	(version 20260206)
	(generator "pcbnew")
	(generator_version "10.0")
	(general
		(thickness 1.6)
		(legacy_teardrops no)
	)
	(paper "A4")
	(title_block
		(title "04192023_DAF0TMB3IC0_F0TG_MB_C_brd_V02_OCP.brd")
		(comment 1 "Grand Teton / footprints 5942-5944 of 8354")
	)
	(layers
		(0 "F.Cu" signal "TOP")
		(4 "In1.Cu" signal "GND")
		(6 "In2.Cu" signal "IN1")
		(8 "In3.Cu" signal "GND1")
		(10 "In4.Cu" signal "IN2")
		(12 "In5.Cu" signal "GND2")
		(14 "In6.Cu" signal "IN3")
		(16 "In7.Cu" signal "GND3")
		(18 "In8.Cu" signal "VCC")
		(20 "In9.Cu" signal "VCC1")
		(22 "In10.Cu" signal "GND4")
		(24 "In11.Cu" signal "IN4")
		(26 "In12.Cu" signal "GND5")
		(28 "In13.Cu" signal "IN5")
		(30 "In14.Cu" signal "GND6")
		(32 "In15.Cu" signal "IN6")
		(34 "In16.Cu" signal "GND7")
		(2 "B.Cu" signal "BOTTOM")
		(9 "F.Adhes" user "F.Adhesive")
		(11 "B.Adhes" user "B.Adhesive")
		(13 "F.Paste" user "Package Geometry/Pastemask Top")
		(15 "B.Paste" user "Package Geometry/Pastemask Bottom")
		(5 "F.SilkS" user "Ref Des/Silkscreen Top")
		(7 "B.SilkS" user "Ref Des/Silkscreen Bottom")
		(1 "F.Mask" user "Board Geometry/Soldermask Top")
		(3 "B.Mask" user "Board Geometry/Soldermask Bottom")
		(17 "Dwgs.User" user "User.Drawings")
		(19 "Cmts.User" user "User.Comments")
		(21 "Eco1.User" user "User.Eco1")
		(23 "Eco2.User" user "User.Eco2")
		(25 "Edge.Cuts" user "Board Geometry/Outline")
		(27 "Margin" user)
		(31 "F.CrtYd" user "Package Geometry/Place Bound Top")
		(29 "B.CrtYd" user "Package Geometry/Place Bound Bottom")
		(35 "F.Fab" user "Ref Des/Assembly Top")
		(33 "B.Fab" user "Ref Des/Assembly Bottom")
	)
	(footprint ""
		(layer "B.Cu")
		(at 106.212386 -251.781564)
		(property "Reference" "C2448"
			(at 0 0 0)
			(layer "B.SilkS")
			(hide yes)
			(effects
				(font
					(size 1.27 1.27)
				)
				(justify mirror)
			)
		)
		(property "Value" ""
			(at 0 0 0)
			(layer "B.Fab")
			(effects
				(font
					(size 1.27 1.27)
				)
				(justify mirror)
			)
		)
		(duplicate_pad_numbers_are_jumpers no)
		(fp_line
			(start -0.7874 -0.4064)
			(end -0.7874 0.4064)
			(stroke
				(width 0.1524)
				(type default)
			)
			(layer "B.SilkS")
		)
		(fp_line
			(start -0.7874 0.4064)
			(end 0.7874 0.4064)
			(stroke
				(width 0.1524)
				(type default)
			)
			(layer "B.SilkS")
		)
		(fp_line
			(start 0.7874 -0.4064)
			(end -0.7874 -0.4064)
			(stroke
				(width 0.1524)
				(type default)
			)
			(layer "B.SilkS")
		)
		(fp_line
			(start 0.7874 0.4064)
			(end 0.7874 -0.4064)
			(stroke
				(width 0.1524)
				(type default)
			)
			(layer "B.SilkS")
		)
		(fp_line
			(start -0.67945 -0.3048)
			(end -0.67945 0.3048)
			(stroke
				(width 0.1)
				(type default)
			)
			(layer "B.Fab")
		)
		(fp_line
			(start -0.67945 0.3048)
			(end -0.120396 0.3048)
			(stroke
				(width 0.1)
				(type default)
			)
			(layer "B.Fab")
		)
		(fp_line
			(start -0.12065 -0.3048)
			(end -0.67945 -0.3048)
			(stroke
				(width 0.1)
				(type default)
			)
			(layer "B.Fab")
		)
		(fp_line
			(start -0.12065 -0.2794)
			(end -0.12065 -0.3048)
			(stroke
				(width 0.1)
				(type default)
			)
			(layer "B.Fab")
		)
		(fp_line
			(start -0.120396 0.2794)
			(end 0.12065 0.2794)
			(stroke
				(width 0.1)
				(type default)
			)
			(layer "B.Fab")
		)
		(fp_line
			(start -0.120396 0.3048)
			(end -0.120396 0.2794)
			(stroke
				(width 0.1)
				(type default)
			)
			(layer "B.Fab")
		)
		(fp_line
			(start 0.12065 -0.305054)
			(end 0.12065 -0.2794)
			(stroke
				(width 0.1)
				(type default)
			)
			(layer "B.Fab")
		)
		(fp_line
			(start 0.12065 -0.2794)
			(end -0.12065 -0.2794)
			(stroke
				(width 0.1)
				(type default)
			)
			(layer "B.Fab")
		)
		(fp_line
			(start 0.12065 0.2794)
			(end 0.12065 0.3048)
			(stroke
				(width 0.1)
				(type default)
			)
			(layer "B.Fab")
		)
		(fp_line
			(start 0.12065 0.3048)
			(end 0.67945 0.3048)
			(stroke
				(width 0.1)
				(type default)
			)
			(layer "B.Fab")
		)
		(fp_line
			(start 0.67945 -0.305054)
			(end 0.12065 -0.305054)
			(stroke
				(width 0.1)
				(type default)
			)
			(layer "B.Fab")
		)
		(fp_line
			(start 0.67945 0.3048)
			(end 0.67945 -0.305054)
			(stroke
				(width 0.1)
				(type default)
			)
			(layer "B.Fab")
		)
		(pad "1" smd circle
			(at 0.40005 0 180)
			(size 0 0)
			(layers "B.Cu" "B.Mask" "B.Paste")
			(net "PVDDCR_SOC_P1")
		)
		(pad "2" smd circle
			(at -0.40005 0 180)
			(size 0 0)
			(layers "B.Cu" "B.Mask" "B.Paste")
			(net "GND")
		)
	)
	(footprint ""
		(layer "B.Cu")
		(at 105.224834 -245.487952)
		(property "Reference" "C2309"
			(at 0 0 0)
			(layer "B.SilkS")
			(hide yes)
			(effects
				(font
					(size 1.27 1.27)
				)
				(justify mirror)
			)
		)
		(property "Value" ""
			(at 0 0 0)
			(layer "B.Fab")
			(effects
				(font
					(size 1.27 1.27)
				)
				(justify mirror)
			)
		)
		(duplicate_pad_numbers_are_jumpers no)
		(fp_line
			(start -0.7874 -0.4064)
			(end -0.7874 0.4064)
			(stroke
				(width 0.1524)
				(type default)
			)
			(layer "B.SilkS")
		)
		(fp_line
			(start -0.7874 0.4064)
			(end 0.7874 0.4064)
			(stroke
				(width 0.1524)
				(type default)
			)
			(layer "B.SilkS")
		)
		(fp_line
			(start 0.7874 -0.4064)
			(end -0.7874 -0.4064)
			(stroke
				(width 0.1524)
				(type default)
			)
			(layer "B.SilkS")
		)
		(fp_line
			(start 0.7874 0.4064)
			(end 0.7874 -0.4064)
			(stroke
				(width 0.1524)
				(type default)
			)
			(layer "B.SilkS")
		)
		(fp_line
			(start -0.67945 -0.3048)
			(end -0.67945 0.3048)
			(stroke
				(width 0.1)
				(type default)
			)
			(layer "B.Fab")
		)
		(fp_line
			(start -0.67945 0.3048)
			(end -0.120396 0.3048)
			(stroke
				(width 0.1)
				(type default)
			)
			(layer "B.Fab")
		)
		(fp_line
			(start -0.12065 -0.3048)
			(end -0.67945 -0.3048)
			(stroke
				(width 0.1)
				(type default)
			)
			(layer "B.Fab")
		)
		(fp_line
			(start -0.12065 -0.2794)
			(end -0.12065 -0.3048)
			(stroke
				(width 0.1)
				(type default)
			)
			(layer "B.Fab")
		)
		(fp_line
			(start -0.120396 0.2794)
			(end 0.12065 0.2794)
			(stroke
				(width 0.1)
				(type default)
			)
			(layer "B.Fab")
		)
		(fp_line
			(start -0.120396 0.3048)
			(end -0.120396 0.2794)
			(stroke
				(width 0.1)
				(type default)
			)
			(layer "B.Fab")
		)
		(fp_line
			(start 0.12065 -0.305054)
			(end 0.12065 -0.2794)
			(stroke
				(width 0.1)
				(type default)
			)
			(layer "B.Fab")
		)
		(fp_line
			(start 0.12065 -0.2794)
			(end -0.12065 -0.2794)
			(stroke
				(width 0.1)
				(type default)
			)
			(layer "B.Fab")
		)
		(fp_line
			(start 0.12065 0.2794)
			(end 0.12065 0.3048)
			(stroke
				(width 0.1)
				(type default)
			)
			(layer "B.Fab")
		)
		(fp_line
			(start 0.12065 0.3048)
			(end 0.67945 0.3048)
			(stroke
				(width 0.1)
				(type default)
			)
			(layer "B.Fab")
		)
		(fp_line
			(start 0.67945 -0.305054)
			(end 0.12065 -0.305054)
			(stroke
				(width 0.1)
				(type default)
			)
			(layer "B.Fab")
		)
		(fp_line
			(start 0.67945 0.3048)
			(end 0.67945 -0.305054)
			(stroke
				(width 0.1)
				(type default)
			)
			(layer "B.Fab")
		)
		(pad "1" smd circle
			(at 0.40005 0 180)
			(size 0 0)
			(layers "B.Cu" "B.Mask" "B.Paste")
			(net "PVDDCR_CPU0_P1")
		)
		(pad "2" smd circle
			(at -0.40005 0 180)
			(size 0 0)
			(layers "B.Cu" "B.Mask" "B.Paste")
			(net "GND")
		)
	)
	(footprint ""
		(layer "B.Cu")
		(at 404.206202 -395.148562 90)
		(property "Reference" "C797"
			(at 0 0 90)
			(layer "B.SilkS")
			(hide yes)
			(effects
				(font
					(size 1.27 1.27)
				)
				(justify mirror)
			)
		)
		(property "Value" ""
			(at 0 0 90)
			(layer "B.Fab")
			(effects
				(font
					(size 1.27 1.27)
				)
				(justify mirror)
			)
		)
		(duplicate_pad_numbers_are_jumpers no)
		(fp_line
			(start 0.299974 -0.150114)
			(end -0.299974 -0.150114)
			(stroke
				(width 0.1)
				(type default)
			)
			(layer "B.Fab")
		)
		(fp_line
			(start -0.299974 -0.150114)
			(end -0.299974 0.150114)
			(stroke
				(width 0.1)
				(type default)
			)
			(layer "B.Fab")
		)
		(fp_line
			(start 0.299974 0.150114)
			(end 0.299974 -0.150114)
			(stroke
				(width 0.1)
				(type default)
			)
			(layer "B.Fab")
		)
		(fp_line
			(start -0.299974 0.150114)
			(end 0.299974 0.150114)
			(stroke
				(width 0.1)
				(type default)
			)
			(layer "B.Fab")
		)
		(pad "1" smd rect
			(at 0.2667 0 270)
			(size 0.3048 0.381)
			(layers "B.Cu" "B.Mask" "B.Paste")
			(net "P0V9_CPU0_RT2_2A")
		)
		(pad "2" smd rect
			(at -0.2667 0 270)
			(size 0.3048 0.381)
			(layers "B.Cu" "B.Mask" "B.Paste")
			(net "GND")
		)
	)
)
